(kicad_pcb
	(version 20241229)
	(generator "pcbnew")
	(generator_version "9.0")
	(general
		(thickness 1.62)
		(legacy_teardrops no)
	)
	(paper "A3")
	(title_block
		(title "COM Express 7 Baseboard")
		(date "2025-02-04")
		(rev "1.1.2")
		(company "Antmicro Ltd")
		(comment 1 "www.antmicro.com")
		(comment 9 "footprints 525-529 of 802")
	)
	(layers
		(0 "F.Cu" signal)
		(4 "In1.Cu" signal)
		(6 "In2.Cu" signal)
		(8 "In3.Cu" signal)
		(10 "In4.Cu" signal)
		(12 "In5.Cu" signal)
		(14 "In6.Cu" signal)
		(2 "B.Cu" signal)
		(9 "F.Adhes" user "F.Adhesive")
		(11 "B.Adhes" user "B.Adhesive")
		(13 "F.Paste" user)
		(15 "B.Paste" user)
		(5 "F.SilkS" user "F.Silkscreen")
		(7 "B.SilkS" user "B.Silkscreen")
		(1 "F.Mask" user)
		(3 "B.Mask" user)
		(17 "Dwgs.User" user "User.Drawings")
		(19 "Cmts.User" user "User.Comments")
		(21 "Eco1.User" user "User.Eco1")
		(23 "Eco2.User" user "User.Eco2")
		(25 "Edge.Cuts" user)
		(27 "Margin" user)
		(31 "F.CrtYd" user "F.Courtyard")
		(29 "B.CrtYd" user "B.Courtyard")
		(35 "F.Fab" user)
		(33 "B.Fab" user)
	)
	(footprint "antmicro-footprints:C_0603_1608Metric"
		(layer "B.Cu")
		(at 104.65 154.46 180)
		(descr "Capacitor SMD 0603")
		(tags "capacitor 0603")
		(property "Reference" "C38"
			(at -3.3 -0.45 0)
			(layer "B.SilkS")
			(effects
				(font
					(size 0.7 0.7)
					(thickness 0.15)
				)
				(justify left bottom mirror)
			)
		)
		(property "Value" "C_22u_16V_0603"
			(at -1.42757 -1.770288 0)
			(layer "B.Fab")
			(effects
				(font
					(size 0.7 0.7)
					(thickness 0.15)
				)
				(justify left bottom mirror)
			)
		)
		(property "Datasheet" "https://product.samsungsem.com/mlcc/CL10A226MO7JZN.do"
			(at 0 0 180)
			(layer "F.Fab")
			(hide yes)
			(effects
				(font
					(size 1.27 1.27)
					(thickness 0.15)
				)
			)
		)
		(property "Author" "Antmicro"
			(at 209.3 308.92 0)
			(layer "B.Fab")
			(hide yes)
			(effects
				(font
					(size 1 1)
					(thickness 0.15)
				)
				(justify mirror)
			)
		)
		(property "Dielectric" ""
			(at 209.3 308.92 0)
			(layer "B.Fab")
			(hide yes)
			(effects
				(font
					(size 1 1)
					(thickness 0.15)
				)
				(justify mirror)
			)
		)
		(property "License" "Apache-2.0"
			(at 209.3 308.92 0)
			(layer "B.Fab")
			(hide yes)
			(effects
				(font
					(size 1 1)
					(thickness 0.15)
				)
				(justify mirror)
			)
		)
		(property "MPN" "CL10A226MO7JZNC"
			(at 209.3 308.92 0)
			(layer "B.Fab")
			(hide yes)
			(effects
				(font
					(size 1 1)
					(thickness 0.15)
				)
				(justify mirror)
			)
		)
		(property "Manufacturer" "Samsung Electro-Mechanics"
			(at 209.3 308.92 0)
			(layer "B.Fab")
			(hide yes)
			(effects
				(font
					(size 1 1)
					(thickness 0.15)
				)
				(justify mirror)
			)
		)
		(property "Public" "False"
			(at 209.3 308.92 0)
			(layer "B.Fab")
			(hide yes)
			(effects
				(font
					(size 1 1)
					(thickness 0.15)
				)
				(justify mirror)
			)
		)
		(property "Val" "22u"
			(at 209.3 308.92 0)
			(layer "B.Fab")
			(hide yes)
			(effects
				(font
					(size 1 1)
					(thickness 0.15)
				)
				(justify mirror)
			)
		)
		(property "Voltage" "16V"
			(at 209.3 308.92 0)
			(layer "B.Fab")
			(hide yes)
			(effects
				(font
					(size 1 1)
					(thickness 0.15)
				)
				(justify mirror)
			)
		)
		(sheetname "OCuLink")
		(sheetfile "oculink.kicad_sch")
		(attr smd)
		(fp_line
			(start 0.15 0.4)
			(end -0.15 0.4)
			(stroke
				(width 0.15)
				(type solid)
			)
			(layer "B.SilkS")
		)
		(fp_line
			(start 0.15 -0.4)
			(end -0.15 -0.4)
			(stroke
				(width 0.15)
				(type solid)
			)
			(layer "B.SilkS")
		)
		(fp_rect
			(start -1.25 0.65)
			(end 1.25 -0.65)
			(stroke
				(width 0.05)
				(type solid)
			)
			(fill no)
			(layer "B.CrtYd")
		)
		(fp_rect
			(start -0.8 0.4)
			(end 0.8 -0.4)
			(stroke
				(width 0.15)
				(type solid)
			)
			(fill no)
			(layer "B.Fab")
		)
		(pad "1" smd roundrect
			(at -0.7 0 180)
			(size 0.8 1)
			(layers "B.Cu" "B.Mask" "B.Paste")
			(roundrect_rratio 0.2)
			(net 1 "GND")
			(pintype "passive")
			(teardrops
				(best_length_ratio 0.2)
				(max_length 1)
				(best_width_ratio 0.9)
				(max_width 2)
				(curved_edges yes)
				(filter_ratio 0.9)
				(enabled yes)
				(allow_two_segments yes)
				(prefer_zone_connections yes)
			)
		)
		(pad "2" smd roundrect
			(at 0.7 0 180)
			(size 0.8 1)
			(layers "B.Cu" "B.Mask" "B.Paste")
			(roundrect_rratio 0.2)
			(net 61 "/OCuLink/5V_CONN0")
			(pintype "passive")
			(teardrops
				(best_length_ratio 0.2)
				(max_length 1)
				(best_width_ratio 0.9)
				(max_width 2)
				(curved_edges yes)
				(filter_ratio 0.9)
				(enabled yes)
				(allow_two_segments yes)
				(prefer_zone_connections yes)
			)
		)
	)
	(footprint "antmicro-footprints:C_0402_1005Metric"
		(layer "B.Cu")
		(at 152.05 168.24 -90)
		(descr "Capacitor SMD 0402")
		(tags "capacitor SMD 0402")
		(property "Reference" "C213"
			(at -1.43 -1.4 90)
			(layer "B.SilkS")
			(effects
				(font
					(size 0.7 0.7)
					(thickness 0.15)
				)
				(justify left bottom mirror)
			)
		)
		(property "Value" "C_100n_0402"
			(at -1.022927 -2.155213 90)
			(layer "B.Fab")
			(effects
				(font
					(size 0.7 0.7)
					(thickness 0.15)
				)
				(justify left bottom mirror)
			)
		)
		(property "Datasheet" "https://www.murata.com/products/productdetail?partno=GRM155R61H104KE14%23"
			(at 0 0 270)
			(layer "F.Fab")
			(hide yes)
			(effects
				(font
					(size 1.27 1.27)
					(thickness 0.15)
				)
			)
		)
		(property "Author" "Antmicro"
			(at -16.19 320.29 0)
			(layer "B.Fab")
			(hide yes)
			(effects
				(font
					(size 1 1)
					(thickness 0.15)
				)
				(justify mirror)
			)
		)
		(property "Dielectric" "X5R"
			(at -16.19 320.29 0)
			(layer "B.Fab")
			(hide yes)
			(effects
				(font
					(size 1 1)
					(thickness 0.15)
				)
				(justify mirror)
			)
		)
		(property "License" "Apache-2.0"
			(at -16.19 320.29 0)
			(layer "B.Fab")
			(hide yes)
			(effects
				(font
					(size 1 1)
					(thickness 0.15)
				)
				(justify mirror)
			)
		)
		(property "MPN" "GRM155R61H104KE14D"
			(at -16.19 320.29 0)
			(layer "B.Fab")
			(hide yes)
			(effects
				(font
					(size 1 1)
					(thickness 0.15)
				)
				(justify mirror)
			)
		)
		(property "Manufacturer" "Murata"
			(at -16.19 320.29 0)
			(layer "B.Fab")
			(hide yes)
			(effects
				(font
					(size 1 1)
					(thickness 0.15)
				)
				(justify mirror)
			)
		)
		(property "Public" "False"
			(at -16.19 320.29 0)
			(layer "B.Fab")
			(hide yes)
			(effects
				(font
					(size 1 1)
					(thickness 0.15)
				)
				(justify mirror)
			)
		)
		(property "Val" "100n"
			(at -16.19 320.29 0)
			(layer "B.Fab")
			(hide yes)
			(effects
				(font
					(size 1 1)
					(thickness 0.15)
				)
				(justify mirror)
			)
		)
		(property "Voltage" "50V"
			(at -16.19 320.29 0)
			(layer "B.Fab")
			(hide yes)
			(effects
				(font
					(size 1 1)
					(thickness 0.15)
				)
				(justify mirror)
			)
		)
		(sheetname "2xSFP+")
		(sheetfile "2xSFP+.kicad_sch")
		(attr smd)
		(fp_rect
			(start -0.925 0.47)
			(end 0.925 -0.47)
			(stroke
				(width 0.05)
				(type default)
			)
			(fill no)
			(layer "B.CrtYd")
		)
		(fp_line
			(start -0.494 0.25)
			(end -0.494 -0.248)
			(stroke
				(width 0.15)
				(type solid)
			)
			(layer "B.Fab")
		)
		(fp_line
			(start 0.504 0.25)
			(end -0.494 0.25)
			(stroke
				(width 0.15)
				(type solid)
			)
			(layer "B.Fab")
		)
		(fp_line
			(start -0.494 -0.248)
			(end 0.504 -0.248)
			(stroke
				(width 0.15)
				(type solid)
			)
			(layer "B.Fab")
		)
		(fp_line
			(start 0.504 -0.248)
			(end 0.504 0.25)
			(stroke
				(width 0.15)
				(type solid)
			)
			(layer "B.Fab")
		)
		(pad "1" smd roundrect
			(at -0.48 0 270)
			(size 0.59 0.64)
			(layers "B.Cu" "B.Mask" "B.Paste")
			(roundrect_rratio 0.25)
			(net 53 "/2xSFP+/SH")
			(pintype "passive")
			(teardrops
				(best_length_ratio 0.2)
				(max_length 1)
				(best_width_ratio 0.9)
				(max_width 2)
				(curved_edges yes)
				(filter_ratio 0.9)
				(enabled yes)
				(allow_two_segments yes)
				(prefer_zone_connections yes)
			)
		)
		(pad "2" smd roundrect
			(at 0.48 0 270)
			(size 0.59 0.64)
			(layers "B.Cu" "B.Mask" "B.Paste")
			(roundrect_rratio 0.25)
			(net 1 "GND")
			(pintype "passive")
			(teardrops
				(best_length_ratio 0.2)
				(max_length 1)
				(best_width_ratio 0.9)
				(max_width 2)
				(curved_edges yes)
				(filter_ratio 0.9)
				(enabled yes)
				(allow_two_segments yes)
				(prefer_zone_connections yes)
			)
		)
	)
	(footprint "antmicro-footprints:R_0402_1005Metric"
		(layer "B.Cu")
		(at 141.05 169.16 -90)
		(descr "Resistor SMD 0402")
		(tags "resistor SMD 0402")
		(property "Reference" "R56"
			(at -3.9 13.5 90)
			(layer "B.SilkS")
			(effects
				(font
					(size 0.7 0.7)
					(thickness 0.15)
				)
				(justify left bottom mirror)
			)
		)
		(property "Value" "R_1k_0402"
			(at -1.011843 -1.772047 90)
			(layer "B.Fab")
			(effects
				(font
					(size 0.7 0.7)
					(thickness 0.15)
				)
				(justify left bottom mirror)
			)
		)
		(property "Datasheet" "https://www.bourns.com/docs/product-datasheets/cr.pdf"
			(at 0 0 270)
			(layer "F.Fab")
			(hide yes)
			(effects
				(font
					(size 1.27 1.27)
					(thickness 0.15)
				)
			)
		)
		(property "Author" "Antmicro"
			(at -28.11 310.21 0)
			(layer "B.Fab")
			(hide yes)
			(effects
				(font
					(size 1 1)
					(thickness 0.15)
				)
				(justify mirror)
			)
		)
		(property "License" "Apache-2.0"
			(at -28.11 310.21 0)
			(layer "B.Fab")
			(hide yes)
			(effects
				(font
					(size 1 1)
					(thickness 0.15)
				)
				(justify mirror)
			)
		)
		(property "MPN" "CR0402-FX-1001GLF"
			(at -28.11 310.21 0)
			(layer "B.Fab")
			(hide yes)
			(effects
				(font
					(size 1 1)
					(thickness 0.15)
				)
				(justify mirror)
			)
		)
		(property "Manufacturer" "Bourns"
			(at -28.11 310.21 0)
			(layer "B.Fab")
			(hide yes)
			(effects
				(font
					(size 1 1)
					(thickness 0.15)
				)
				(justify mirror)
			)
		)
		(property "Public" "False"
			(at -28.11 310.21 0)
			(layer "B.Fab")
			(hide yes)
			(effects
				(font
					(size 1 1)
					(thickness 0.15)
				)
				(justify mirror)
			)
		)
		(property "Tolerance" "1%"
			(at -28.11 310.21 0)
			(layer "B.Fab")
			(hide yes)
			(effects
				(font
					(size 1 1)
					(thickness 0.15)
				)
				(justify mirror)
			)
		)
		(property "Val" "1k"
			(at -28.11 310.21 0)
			(layer "B.Fab")
			(hide yes)
			(effects
				(font
					(size 1 1)
					(thickness 0.15)
				)
				(justify mirror)
			)
		)
		(sheetname "2xSFP+")
		(sheetfile "2xSFP+.kicad_sch")
		(attr smd)
		(fp_rect
			(start -0.925 0.47)
			(end 0.925 -0.47)
			(stroke
				(width 0.05)
				(type default)
			)
			(fill no)
			(layer "B.CrtYd")
		)
		(fp_rect
			(start -0.5 0.25)
			(end 0.5 -0.25)
			(stroke
				(width 0.15)
				(type solid)
			)
			(fill no)
			(layer "B.Fab")
		)
		(pad "1" smd roundrect
			(at -0.48 0 270)
			(size 0.59 0.64)
			(layers "B.Cu" "B.Mask" "B.Paste")
			(roundrect_rratio 0.25)
			(net 894 "Net-(J2B-MOD_{ABS})")
			(pintype "passive")
			(teardrops
				(best_length_ratio 0.2)
				(max_length 1)
				(best_width_ratio 0.9)
				(max_width 2)
				(curved_edges yes)
				(filter_ratio 0.9)
				(enabled yes)
				(allow_two_segments yes)
				(prefer_zone_connections yes)
			)
		)
		(pad "2" smd roundrect
			(at 0.48 0 270)
			(size 0.59 0.64)
			(layers "B.Cu" "B.Mask" "B.Paste")
			(roundrect_rratio 0.25)
			(net 2 "+3V3")
			(pintype "passive")
			(teardrops
				(best_length_ratio 0.2)
				(max_length 1)
				(best_width_ratio 0.9)
				(max_width 2)
				(curved_edges yes)
				(filter_ratio 0.9)
				(enabled yes)
				(allow_two_segments yes)
				(prefer_zone_connections yes)
			)
		)
	)
	(footprint "antmicro-footprints:R_0402_1005Metric"
		(layer "B.Cu")
		(at 308.824999 101.76 -90)
		(descr "Resistor SMD 0402")
		(tags "resistor SMD 0402")
		(property "Reference" "R87"
			(at -3.06 -0.455001 90)
			(layer "B.SilkS")
			(effects
				(font
					(size 0.7 0.7)
					(thickness 0.15)
				)
				(justify left bottom mirror)
			)
		)
		(property "Value" "R_30k_0402"
			(at -1.011843 -1.772047 90)
			(layer "B.Fab")
			(effects
				(font
					(size 0.7 0.7)
					(thickness 0.15)
				)
				(justify left bottom mirror)
			)
		)
		(property "Datasheet" "https://www.bourns.com/docs/product-datasheets/cr.pdf"
			(at 0 0 270)
			(layer "F.Fab")
			(hide yes)
			(effects
				(font
					(size 1.27 1.27)
					(thickness 0.15)
				)
			)
		)
		(property "Author" "Antmicro"
			(at 207.064999 410.584999 0)
			(layer "B.Fab")
			(hide yes)
			(effects
				(font
					(size 1 1)
					(thickness 0.15)
				)
				(justify mirror)
			)
		)
		(property "License" "Apache-2.0"
			(at 207.064999 410.584999 0)
			(layer "B.Fab")
			(hide yes)
			(effects
				(font
					(size 1 1)
					(thickness 0.15)
				)
				(justify mirror)
			)
		)
		(property "MPN" "CR0402-FX-3002GLF"
			(at 207.064999 410.584999 0)
			(layer "B.Fab")
			(hide yes)
			(effects
				(font
					(size 1 1)
					(thickness 0.15)
				)
				(justify mirror)
			)
		)
		(property "Manufacturer" "Bourns"
			(at 207.064999 410.584999 0)
			(layer "B.Fab")
			(hide yes)
			(effects
				(font
					(size 1 1)
					(thickness 0.15)
				)
				(justify mirror)
			)
		)
		(property "Public" "False"
			(at 207.064999 410.584999 0)
			(layer "B.Fab")
			(hide yes)
			(effects
				(font
					(size 1 1)
					(thickness 0.15)
				)
				(justify mirror)
			)
		)
		(property "Tolerance" "1%"
			(at 207.064999 410.584999 0)
			(layer "B.Fab")
			(hide yes)
			(effects
				(font
					(size 1 1)
					(thickness 0.15)
				)
				(justify mirror)
			)
		)
		(property "Val" "30k"
			(at 207.064999 410.584999 0)
			(layer "B.Fab")
			(hide yes)
			(effects
				(font
					(size 1 1)
					(thickness 0.15)
				)
				(justify mirror)
			)
		)
		(sheetname "Power")
		(sheetfile "power.kicad_sch")
		(attr smd)
		(fp_rect
			(start -0.925 0.47)
			(end 0.925 -0.47)
			(stroke
				(width 0.05)
				(type default)
			)
			(fill no)
			(layer "B.CrtYd")
		)
		(fp_rect
			(start -0.5 0.25)
			(end 0.5 -0.25)
			(stroke
				(width 0.15)
				(type solid)
			)
			(fill no)
			(layer "B.Fab")
		)
		(pad "1" smd roundrect
			(at -0.48 0 270)
			(size 0.59 0.64)
			(layers "B.Cu" "B.Mask" "B.Paste")
			(roundrect_rratio 0.25)
			(net 574 "Net-(U19-EN)")
			(pintype "passive")
			(teardrops
				(best_length_ratio 0.2)
				(max_length 1)
				(best_width_ratio 0.9)
				(max_width 2)
				(curved_edges yes)
				(filter_ratio 0.9)
				(enabled yes)
				(allow_two_segments yes)
				(prefer_zone_connections yes)
			)
		)
		(pad "2" smd roundrect
			(at 0.48 0 270)
			(size 0.59 0.64)
			(layers "B.Cu" "B.Mask" "B.Paste")
			(roundrect_rratio 0.25)
			(net 1 "GND")
			(pintype "passive")
			(teardrops
				(best_length_ratio 0.2)
				(max_length 1)
				(best_width_ratio 0.9)
				(max_width 2)
				(curved_edges yes)
				(filter_ratio 0.9)
				(enabled yes)
				(allow_two_segments yes)
				(prefer_zone_connections yes)
			)
		)
	)
	(footprint "antmicro-footprints:C_0402_1005Metric"
		(layer "B.Cu")
		(at 143.377 149.258 -90)
		(descr "Capacitor SMD 0402")
		(tags "capacitor SMD 0402")
		(property "Reference" "C149"
			(at -1.398 1.427 90)
			(layer "B.SilkS")
			(effects
				(font
					(size 0.7 0.7)
					(thickness 0.15)
				)
				(justify left bottom mirror)
			)
		)
		(property "Value" "C_100n_0402"
			(at -1.022927 -2.155213 90)
			(layer "B.Fab")
			(effects
				(font
					(size 0.7 0.7)
					(thickness 0.15)
				)
				(justify left bottom mirror)
			)
		)
		(property "Datasheet" "https://www.murata.com/products/productdetail?partno=GRM155R61H104KE14%23"
			(at 0 0 270)
			(layer "F.Fab")
			(hide yes)
			(effects
				(font
					(size 1.27 1.27)
					(thickness 0.15)
				)
			)
		)
		(property "Author" "Antmicro"
			(at -5.881 292.635 0)
			(layer "B.Fab")
			(hide yes)
			(effects
				(font
					(size 1 1)
					(thickness 0.15)
				)
				(justify mirror)
			)
		)
		(property "Dielectric" "X5R"
			(at -5.881 292.635 0)
			(layer "B.Fab")
			(hide yes)
			(effects
				(font
					(size 1 1)
					(thickness 0.15)
				)
				(justify mirror)
			)
		)
		(property "License" "Apache-2.0"
			(at -5.881 292.635 0)
			(layer "B.Fab")
			(hide yes)
			(effects
				(font
					(size 1 1)
					(thickness 0.15)
				)
				(justify mirror)
			)
		)
		(property "MPN" "GRM155R61H104KE14D"
			(at -5.881 292.635 0)
			(layer "B.Fab")
			(hide yes)
			(effects
				(font
					(size 1 1)
					(thickness 0.15)
				)
				(justify mirror)
			)
		)
		(property "Manufacturer" "Murata"
			(at -5.881 292.635 0)
			(layer "B.Fab")
			(hide yes)
			(effects
				(font
					(size 1 1)
					(thickness 0.15)
				)
				(justify mirror)
			)
		)
		(property "Public" "False"
			(at -5.881 292.635 0)
			(layer "B.Fab")
			(hide yes)
			(effects
				(font
					(size 1 1)
					(thickness 0.15)
				)
				(justify mirror)
			)
		)
		(property "Val" "100n"
			(at -5.881 292.635 0)
			(layer "B.Fab")
			(hide yes)
			(effects
				(font
					(size 1 1)
					(thickness 0.15)
				)
				(justify mirror)
			)
		)
		(property "Voltage" "50V"
			(at -5.881 292.635 0)
			(layer "B.Fab")
			(hide yes)
			(effects
				(font
					(size 1 1)
					(thickness 0.15)
				)
				(justify mirror)
			)
		)
		(sheetname "KR to SFI #1")
		(sheetfile "kr_sfi.kicad_sch")
		(attr smd)
		(fp_rect
			(start -0.925 0.47)
			(end 0.925 -0.47)
			(stroke
				(width 0.05)
				(type default)
			)
			(fill no)
			(layer "B.CrtYd")
		)
		(fp_line
			(start -0.494 0.25)
			(end -0.494 -0.248)
			(stroke
				(width 0.15)
				(type solid)
			)
			(layer "B.Fab")
		)
		(fp_line
			(start 0.504 0.25)
			(end -0.494 0.25)
			(stroke
				(width 0.15)
				(type solid)
			)
			(layer "B.Fab")
		)
		(fp_line
			(start -0.494 -0.248)
			(end 0.504 -0.248)
			(stroke
				(width 0.15)
				(type solid)
			)
			(layer "B.Fab")
		)
		(fp_line
			(start 0.504 -0.248)
			(end 0.504 0.25)
			(stroke
				(width 0.15)
				(type solid)
			)
			(layer "B.Fab")
		)
		(pad "1" smd roundrect
			(at -0.48 0 270)
			(size 0.59 0.64)
			(layers "B.Cu" "B.Mask" "B.Paste")
			(roundrect_rratio 0.25)
			(net 1 "GND")
			(pintype "passive")
			(teardrops
				(best_length_ratio 0.2)
				(max_length 1)
				(best_width_ratio 0.9)
				(max_width 2)
				(curved_edges yes)
				(filter_ratio 0.9)
				(enabled yes)
				(allow_two_segments yes)
				(prefer_zone_connections yes)
			)
		)
		(pad "2" smd roundrect
			(at 0.48 0 270)
			(size 0.59 0.64)
			(layers "B.Cu" "B.Mask" "B.Paste")
			(roundrect_rratio 0.25)
			(net 2 "+3V3")
			(pintype "passive")
			(teardrops
				(best_length_ratio 0.2)
				(max_length 1)
				(best_width_ratio 0.9)
				(max_width 2)
				(curved_edges yes)
				(filter_ratio 0.9)
				(enabled yes)
				(allow_two_segments yes)
				(prefer_zone_connections yes)
			)
		)
	)
)
